(kicad_pcb
	(version 20260206)
	(generator "pcbnew")
	(generator_version "10.0")
	(general
		(thickness 1.6)
		(legacy_teardrops no)
	)
	(paper "A4")
	(title_block
		(title "Wiwynn_Tioga_Pass_MB.brd")
		(comment 1 "Tioga Pass / footprints 1375-1381 of 4770")
	)
	(layers
		(0 "F.Cu" signal "TOP")
		(4 "In1.Cu" signal "L2GND")
		(6 "In2.Cu" signal "L3")
		(8 "In3.Cu" signal "L4GND")
		(10 "In4.Cu" signal "L5")
		(12 "In5.Cu" signal "L6GND")
		(14 "In6.Cu" signal "L7VCC")
		(16 "In7.Cu" signal "L8VCC")
		(18 "In8.Cu" signal "L9GND")
		(20 "In9.Cu" signal "L10")
		(22 "In10.Cu" signal "L11GND")
		(24 "In11.Cu" signal "L12")
		(26 "In12.Cu" signal "L13GND")
		(2 "B.Cu" signal "BOTTOM")
		(9 "F.Adhes" user "F.Adhesive")
		(11 "B.Adhes" user "B.Adhesive")
		(13 "F.Paste" user "Package Geometry/Pastemask Top")
		(15 "B.Paste" user "Package Geometry/Pastemask Bottom")
		(5 "F.SilkS" user "Ref Des/Silkscreen Top")
		(7 "B.SilkS" user "Ref Des/Silkscreen Bottom")
		(1 "F.Mask" user "Board Geometry/Soldermask Top")
		(3 "B.Mask" user "Board Geometry/Soldermask Bottom")
		(17 "Dwgs.User" user "User.Drawings")
		(19 "Cmts.User" user "User.Comments")
		(21 "Eco1.User" user "User.Eco1")
		(23 "Eco2.User" user "User.Eco2")
		(25 "Edge.Cuts" user "Board Geometry/Outline")
		(27 "Margin" user)
		(31 "F.CrtYd" user "Package Geometry/Place Bound Top")
		(29 "B.CrtYd" user "Package Geometry/Place Bound Bottom")
		(35 "F.Fab" user "Ref Des/Assembly Top")
		(33 "B.Fab" user "Ref Des/Assembly Bottom")
	)
	(footprint ""
		(layer "F.Cu")
		(at 13.8938 -36.576 90)
		(property "Reference" "C1F2"
			(at 0 0 90)
			(layer "F.SilkS")
			(hide yes)
			(effects
				(font
					(size 1.27 1.27)
				)
			)
		)
		(property "Value" ""
			(at 0 0 90)
			(layer "F.Fab")
			(effects
				(font
					(size 1.27 1.27)
				)
			)
		)
		(duplicate_pad_numbers_are_jumpers no)
		(fp_rect
			(start -0.3048 -0.1016)
			(end 0.3048 0.9906)
			(stroke
				(width 0)
				(type default)
			)
			(fill no)
			(layer "F.CrtYd")
		)
		(fp_line
			(start 0.3048 -0.1016)
			(end -0.3048 -0.1016)
			(stroke
				(width 0.1)
				(type default)
			)
			(layer "F.Fab")
		)
		(fp_line
			(start -0.3048 -0.1016)
			(end -0.3048 0.9906)
			(stroke
				(width 0.1)
				(type default)
			)
			(layer "F.Fab")
		)
		(fp_line
			(start 0.3048 0.9906)
			(end 0.3048 -0.1016)
			(stroke
				(width 0.1)
				(type default)
			)
			(layer "F.Fab")
		)
		(fp_line
			(start -0.3048 0.9906)
			(end 0.3048 0.9906)
			(stroke
				(width 0.1)
				(type default)
			)
			(layer "F.Fab")
		)
		(pad "1" smd rect
			(at 0 0 90)
			(size 0.508 0.508)
			(layers "F.Cu" "F.Mask" "F.Paste")
			(net "P3E_CPU1_PE3_MP_C_TXP<7>")
		)
		(pad "2" smd rect
			(at 0 0.889 90)
			(size 0.508 0.508)
			(layers "F.Cu" "F.Mask" "F.Paste")
			(net "P3E_CPU1_PE3_MP_TXP<7>")
		)
		(zone
			(layer "F.Cu")
			(hatch none 0.5)
			(connect_pads
				(clearance 0)
			)
			(min_thickness 0.25)
			(keepout
				(tracks allowed)
				(vias not_allowed)
				(pads allowed)
				(copperpour not_allowed)
				(footprints allowed)
			)
			(placement
				(enabled no)
				(sheetname "")
			)
			(fill
				(thermal_gap 0.5)
				(thermal_bridge_width 0.5)
				(island_removal_mode 0)
			)
			(polygon
				(pts
					(xy 14.1478 -36.322) (xy 14.5288 -36.322) (xy 14.5288 -36.83) (xy 14.1478 -36.83)
				)
			)
		)
		(zone
			(layer "F.Cu")
			(hatch none 0.5)
			(connect_pads
				(clearance 0)
			)
			(min_thickness 0.25)
			(keepout
				(tracks not_allowed)
				(vias allowed)
				(pads allowed)
				(copperpour not_allowed)
				(footprints allowed)
			)
			(placement
				(enabled no)
				(sheetname "")
			)
			(fill
				(thermal_gap 0.5)
				(thermal_bridge_width 0.5)
				(island_removal_mode 0)
			)
			(polygon
				(pts
					(xy 14.1478 -36.322) (xy 14.5288 -36.322) (xy 14.5288 -36.83) (xy 14.1478 -36.83)
				)
			)
		)
	)
	(footprint ""
		(layer "F.Cu")
		(at 28.575 -13.3731)
		(property "Reference" "R1G2"
			(at 0 0 0)
			(layer "F.SilkS")
			(hide yes)
			(effects
				(font
					(size 1.27 1.27)
				)
			)
		)
		(property "Value" ""
			(at 0 0 0)
			(layer "F.Fab")
			(effects
				(font
					(size 1.27 1.27)
				)
			)
		)
		(duplicate_pad_numbers_are_jumpers no)
		(fp_poly
			(pts
				(xy -0.2794 -0.1016) (xy 0.2794 -0.1016) (xy 0.2794 0.9906) (xy -0.2794 0.9906)
			)
			(stroke
				(width 0)
				(type default)
			)
			(fill no)
			(layer "F.CrtYd")
		)
		(fp_line
			(start -0.2794 -0.1016)
			(end -0.2794 0.9906)
			(stroke
				(width 0.1)
				(type default)
			)
			(layer "F.Fab")
		)
		(fp_line
			(start -0.2794 0.9906)
			(end 0.2794 0.9906)
			(stroke
				(width 0.1)
				(type default)
			)
			(layer "F.Fab")
		)
		(fp_line
			(start 0.2794 -0.1016)
			(end -0.2794 -0.1016)
			(stroke
				(width 0.1)
				(type default)
			)
			(layer "F.Fab")
		)
		(fp_line
			(start 0.2794 0.9906)
			(end 0.2794 -0.1016)
			(stroke
				(width 0.1)
				(type default)
			)
			(layer "F.Fab")
		)
		(pad "1" smd rect
			(at 0 0)
			(size 0.508 0.508)
			(layers "F.Cu" "F.Mask" "F.Paste")
			(net "PVDDQ_GHJ")
		)
		(pad "2" smd rect
			(at 0 0.889)
			(size 0.508 0.508)
			(layers "F.Cu" "F.Mask" "F.Paste")
			(net "M_H_VREF")
		)
		(zone
			(layer "F.Cu")
			(hatch none 0.5)
			(connect_pads
				(clearance 0)
			)
			(min_thickness 0.25)
			(keepout
				(tracks allowed)
				(vias not_allowed)
				(pads allowed)
				(copperpour not_allowed)
				(footprints allowed)
			)
			(placement
				(enabled no)
				(sheetname "")
			)
			(fill
				(thermal_gap 0.5)
				(thermal_bridge_width 0.5)
				(island_removal_mode 0)
			)
			(polygon
				(pts
					(xy 28.321 -13.1191) (xy 28.829 -13.1191) (xy 28.829 -12.7381) (xy 28.321 -12.7381)
				)
			)
		)
		(zone
			(layer "F.Cu")
			(hatch none 0.5)
			(connect_pads
				(clearance 0)
			)
			(min_thickness 0.25)
			(keepout
				(tracks not_allowed)
				(vias allowed)
				(pads allowed)
				(copperpour not_allowed)
				(footprints allowed)
			)
			(placement
				(enabled no)
				(sheetname "")
			)
			(fill
				(thermal_gap 0.5)
				(thermal_bridge_width 0.5)
				(island_removal_mode 0)
			)
			(polygon
				(pts
					(xy 28.321 -12.7381) (xy 28.829 -12.7381) (xy 28.829 -13.1191) (xy 28.321 -13.1191)
				)
			)
		)
	)
	(footprint ""
		(layer "F.Cu")
		(at 29.6418 -102.235 -90)
		(property "Reference" "R1C36"
			(at 0 0 270)
			(layer "F.SilkS")
			(hide yes)
			(effects
				(font
					(size 1.27 1.27)
				)
			)
		)
		(property "Value" ""
			(at 0 0 270)
			(layer "F.Fab")
			(effects
				(font
					(size 1.27 1.27)
				)
			)
		)
		(duplicate_pad_numbers_are_jumpers no)
		(fp_poly
			(pts
				(xy -0.2794 -0.1016) (xy 0.2794 -0.1016) (xy 0.2794 0.9906) (xy -0.2794 0.9906)
			)
			(stroke
				(width 0)
				(type default)
			)
			(fill no)
			(layer "F.CrtYd")
		)
		(fp_line
			(start -0.2794 0.9906)
			(end 0.2794 0.9906)
			(stroke
				(width 0.1)
				(type default)
			)
			(layer "F.Fab")
		)
		(fp_line
			(start 0.2794 0.9906)
			(end 0.2794 -0.1016)
			(stroke
				(width 0.1)
				(type default)
			)
			(layer "F.Fab")
		)
		(fp_line
			(start -0.2794 -0.1016)
			(end -0.2794 0.9906)
			(stroke
				(width 0.1)
				(type default)
			)
			(layer "F.Fab")
		)
		(fp_line
			(start 0.2794 -0.1016)
			(end -0.2794 -0.1016)
			(stroke
				(width 0.1)
				(type default)
			)
			(layer "F.Fab")
		)
		(pad "1" smd rect
			(at 0 0 270)
			(size 0.508 0.508)
			(layers "F.Cu" "F.Mask" "F.Paste")
			(net "FM_CPU1_SM_WP")
		)
		(pad "2" smd rect
			(at 0 0.889 270)
			(size 0.508 0.508)
			(layers "F.Cu" "F.Mask" "F.Paste")
			(net "GND")
		)
		(zone
			(layer "F.Cu")
			(hatch none 0.5)
			(connect_pads
				(clearance 0)
			)
			(min_thickness 0.25)
			(keepout
				(tracks not_allowed)
				(vias allowed)
				(pads allowed)
				(copperpour not_allowed)
				(footprints allowed)
			)
			(placement
				(enabled no)
				(sheetname "")
			)
			(fill
				(thermal_gap 0.5)
				(thermal_bridge_width 0.5)
				(island_removal_mode 0)
			)
			(polygon
				(pts
					(xy 29.0068 -102.489) (xy 29.0068 -101.981) (xy 29.3878 -101.981) (xy 29.3878 -102.489)
				)
			)
		)
		(zone
			(layer "F.Cu")
			(hatch none 0.5)
			(connect_pads
				(clearance 0)
			)
			(min_thickness 0.25)
			(keepout
				(tracks allowed)
				(vias not_allowed)
				(pads allowed)
				(copperpour not_allowed)
				(footprints allowed)
			)
			(placement
				(enabled no)
				(sheetname "")
			)
			(fill
				(thermal_gap 0.5)
				(thermal_bridge_width 0.5)
				(island_removal_mode 0)
			)
			(polygon
				(pts
					(xy 29.3878 -102.489) (xy 29.3878 -101.981) (xy 29.0068 -101.981) (xy 29.0068 -102.489)
				)
			)
		)
	)
	(footprint ""
		(layer "F.Cu")
		(at 26.210514 -117.35435)
		(property "Reference" "L1B2"
			(at 0 0 0)
			(layer "F.SilkS")
			(hide yes)
			(effects
				(font
					(size 1.27 1.27)
				)
			)
		)
		(property "Value" "*"
			(at 4.9784 -0.6477 0)
			(unlocked yes)
			(layer "F.Fab")
			(hide yes)
			(effects
				(font
					(size 1.27 1.016)
					(thickness 0.1524)
				)
			)
		)
		(property "Device Type" "IND-80NH-1-GP_DISCRET-GC2-IND-A"
			(at 4.9784 -2.1717 0)
			(unlocked yes)
			(layer "F.Fab")
			(hide yes)
			(effects
				(font
					(size 1.27 1.016)
					(thickness 0.1524)
				)
			)
		)
		(duplicate_pad_numbers_are_jumpers no)
		(fp_line
			(start -2.8575 -3.4544)
			(end 2.8575 -3.4544)
			(stroke
				(width 0.1524)
				(type default)
			)
			(layer "F.SilkS")
		)
		(fp_line
			(start -2.8575 3.4544)
			(end -2.8575 -3.4544)
			(stroke
				(width 0.1524)
				(type default)
			)
			(layer "F.SilkS")
		)
		(fp_line
			(start 2.8575 -3.4544)
			(end 2.8575 3.4544)
			(stroke
				(width 0.1524)
				(type default)
			)
			(layer "F.SilkS")
		)
		(fp_line
			(start 2.8575 3.4544)
			(end -2.8575 3.4544)
			(stroke
				(width 0.1524)
				(type default)
			)
			(layer "F.SilkS")
		)
		(fp_rect
			(start -2.6035 2.6035)
			(end 2.6035 -2.6035)
			(stroke
				(width 0)
				(type default)
			)
			(fill no)
			(layer "F.CrtYd")
		)
		(fp_poly
			(pts
				(xy -3.1115 3.5306) (xy -3.1115 2.6035) (xy 2.6035 2.6035) (xy 2.6035 -2.6035) (xy -2.6035 -2.6035)
				(xy -2.6035 2.5908) (xy -3.1115 2.5908) (xy -3.1115 -3.5306) (xy 3.1115 -3.5306) (xy 3.1115 3.5306)
			)
			(stroke
				(width 0)
				(type default)
			)
			(fill no)
			(layer "F.CrtYd")
		)
		(fp_rect
			(start -3.1115 3.5306)
			(end 3.1115 -3.5306)
			(stroke
				(width 0)
				(type default)
			)
			(fill no)
			(layer "F.Fab")
		)
		(pad "1" smd rect
			(at 0 -2.395982)
			(size 2.2606 1.6002)
			(layers "F.Cu" "F.Mask" "F.Paste")
			(net "P12V_STBY")
		)
		(pad "2" smd rect
			(at 0 2.395982)
			(size 2.2606 1.6002)
			(layers "F.Cu" "F.Mask" "F.Paste")
			(net "VR_FET_SW_P12V_STBY_PVCCIN_CPU1")
		)
	)
	(footprint ""
		(layer "F.Cu")
		(at 382.490726 -80.941926 90)
		(property "Reference" "U14E2"
			(at -0.14986 2.621788 90)
			(unlocked yes)
			(layer "F.SilkS")
			(effects
				(font
					(size 1.27 0.964946)
					(thickness 0.000001)
				)
				(justify left)
			)
		)
		(property "Value" ""
			(at 0 0 90)
			(layer "F.Fab")
			(effects
				(font
					(size 1.27 1.27)
				)
			)
		)
		(duplicate_pad_numbers_are_jumpers no)
		(fp_circle
			(center -0.4699 -0.8382)
			(end -0.4699 -0.7112)
			(stroke
				(width 0.254)
				(type default)
			)
			(fill no)
			(layer "F.SilkS")
		)
		(fp_poly
			(pts
				(xy 0.21463 -0.450088) (xy 1.56337 -0.450088) (xy 1.56337 1.75006) (xy 0.21463 1.75006)
			)
			(stroke
				(width 0)
				(type default)
			)
			(fill no)
			(layer "F.CrtYd")
		)
		(fp_line
			(start 1.56337 -0.450088)
			(end 1.56337 1.75006)
			(stroke
				(width 0.1)
				(type default)
			)
			(layer "F.Fab")
		)
		(fp_line
			(start 0.21463 -0.450088)
			(end 1.56337 -0.450088)
			(stroke
				(width 0.1)
				(type default)
			)
			(layer "F.Fab")
		)
		(fp_line
			(start 1.56337 1.75006)
			(end 0.21463 1.75006)
			(stroke
				(width 0.1)
				(type default)
			)
			(layer "F.Fab")
		)
		(fp_line
			(start 0.21463 1.75006)
			(end 0.21463 -0.450088)
			(stroke
				(width 0.1)
				(type default)
			)
			(layer "F.Fab")
		)
		(fp_circle
			(center -0.4699 -0.8382)
			(end -0.4699 -0.7112)
			(stroke
				(width 0.254)
				(type default)
			)
			(fill no)
			(layer "F.Fab")
		)
		(pad "1" smd rect
			(at 0 0 90)
			(size 1.016 0.381)
			(layers "F.Cu" "F.Mask" "F.Paste")
			(net "RST_PCIE_M2_DEV_N")
		)
		(pad "2" smd rect
			(at 0 0.649986 90)
			(size 1.016 0.381)
			(layers "F.Cu" "F.Mask" "F.Paste")
			(net "RST_PCIE_M2_DEV_AND")
		)
		(pad "3" smd rect
			(at 0 1.299972 90)
			(size 1.016 0.381)
			(layers "F.Cu" "F.Mask" "F.Paste")
			(net "GND")
		)
		(pad "4" smd rect
			(at 1.778 1.299972 90)
			(size 1.016 0.381)
			(layers "F.Cu" "F.Mask" "F.Paste")
			(net "RST_PCIE_M2_DEV_IC_N")
		)
		(pad "5" smd rect
			(at 1.778 0 90)
			(size 1.016 0.381)
			(layers "F.Cu" "F.Mask" "F.Paste")
			(net "P3V3")
		)
	)
	(footprint ""
		(layer "F.Cu")
		(at 367.603532 12.003278 -90)
		(property "Reference" "T1P24"
			(at 0 0 270)
			(layer "F.SilkS")
			(hide yes)
			(effects
				(font
					(size 1.27 1.27)
				)
			)
		)
		(property "Value" "*"
			(at -3.302 1.12395 270)
			(unlocked yes)
			(layer "F.Fab")
			(hide yes)
			(effects
				(font
					(size 0.889 0.889)
					(thickness 0.1524)
				)
			)
		)
		(property "Device Type" "TPAD-DIFF-4P-GP_DISCRET-GB3-TPA"
			(at -3.302 -0.40005 270)
			(unlocked yes)
			(layer "F.Fab")
			(hide yes)
			(effects
				(font
					(size 0.889 0.889)
					(thickness 0.1524)
				)
			)
		)
		(duplicate_pad_numbers_are_jumpers no)
		(fp_line
			(start -2.286 2.286)
			(end 2.286 2.286)
			(stroke
				(width 0.1524)
				(type default)
			)
			(layer "F.SilkS")
		)
		(fp_line
			(start 2.286 2.286)
			(end 2.286 -2.286)
			(stroke
				(width 0.1524)
				(type default)
			)
			(layer "F.SilkS")
		)
		(fp_line
			(start -2.286 -2.286)
			(end -2.286 2.286)
			(stroke
				(width 0.1524)
				(type default)
			)
			(layer "F.SilkS")
		)
		(fp_line
			(start 2.286 -2.286)
			(end -2.286 -2.286)
			(stroke
				(width 0.1524)
				(type default)
			)
			(layer "F.SilkS")
		)
		(fp_line
			(start -2.413 -2.413)
			(end -2.413 -1.143)
			(stroke
				(width 0.4064)
				(type default)
			)
			(layer "F.SilkS")
		)
		(fp_line
			(start -1.143 -2.413)
			(end -2.413 -2.413)
			(stroke
				(width 0.4064)
				(type default)
			)
			(layer "F.SilkS")
		)
		(fp_rect
			(start -2.54 2.54)
			(end 2.54 -2.54)
			(stroke
				(width 0)
				(type default)
			)
			(fill no)
			(layer "F.CrtYd")
		)
		(fp_rect
			(start -2.54 2.54)
			(end 2.54 -2.54)
			(stroke
				(width 0)
				(type default)
			)
			(fill no)
			(layer "F.Fab")
		)
		(pad "1" thru_hole circle
			(at -1.27 -1.27 270)
			(size 1.524 1.524)
			(drill 0.9144)
			(layers "*.Cu" "*.Mask")
			(remove_unused_layers no)
			(net "L14_100OHM_6INCH_DP")
			(clearance -0.0508)
			(thermal_gap 0.127)
			(padstack
				(mode front_inner_back)
				(layer "Inner"
					(shape circle)
					(size 1.1684 1.1684)
					(clearance 0.127)
				)
				(layer "B.Cu"
					(shape circle)
					(size 1.524 1.524)
					(clearance -0.0508)
				)
			)
		)
		(pad "2" thru_hole circle
			(at 1.27 -1.27 270)
			(size 1.524 1.524)
			(drill 0.9144)
			(layers "*.Cu" "*.Mask")
			(remove_unused_layers no)
			(net "L14_100OHM_6INCH_DN")
			(clearance -0.0508)
			(thermal_gap 0.127)
			(padstack
				(mode front_inner_back)
				(layer "Inner"
					(shape circle)
					(size 1.1684 1.1684)
					(clearance 0.127)
				)
				(layer "B.Cu"
					(shape circle)
					(size 1.524 1.524)
					(clearance -0.0508)
				)
			)
		)
		(pad "GND1" thru_hole rect
			(at -1.27 1.27 270)
			(size 1.524 1.524)
			(drill 0.9144)
			(layers "*.Cu" "*.Mask")
			(remove_unused_layers no)
			(net "GND")
			(clearance -0.0508)
			(thermal_gap 0.127)
			(padstack
				(mode front_inner_back)
				(layer "Inner"
					(shape circle)
					(size 1.1684 1.1684)
					(clearance 0.127)
				)
				(layer "B.Cu"
					(shape rect)
					(size 1.524 1.524)
					(clearance -0.0508)
				)
			)
		)
		(pad "GND2" thru_hole rect
			(at 1.27 1.27 270)
			(size 1.524 1.524)
			(drill 0.9144)
			(layers "*.Cu" "*.Mask")
			(remove_unused_layers no)
			(net "GND")
			(clearance -0.0508)
			(thermal_gap 0.127)
			(padstack
				(mode front_inner_back)
				(layer "Inner"
					(shape circle)
					(size 1.1684 1.1684)
					(clearance 0.127)
				)
				(layer "B.Cu"
					(shape rect)
					(size 1.524 1.524)
					(clearance -0.0508)
				)
			)
		)
	)
	(footprint ""
		(layer "F.Cu")
		(at 25.04186 -93.8911 180)
		(property "Reference" "CF11"
			(at 0 0 180)
			(layer "F.SilkS")
			(hide yes)
			(effects
				(font
					(size 1.27 1.27)
				)
			)
		)
		(property "Value" "*"
			(at 1.1811 -2.8194 180)
			(unlocked yes)
			(layer "F.Fab")
			(hide yes)
			(effects
				(font
					(size 1.27 1.016)
					(thickness 0.1524)
				)
			)
		)
		(property "Device Type" "SC22P50V2JN-4GP_SMD-BCG-SC22P5A"
			(at 1.1811 -4.3434 180)
			(unlocked yes)
			(layer "F.Fab")
			(hide yes)
			(effects
				(font
					(size 1.27 1.016)
					(thickness 0.1524)
				)
			)
		)
		(duplicate_pad_numbers_are_jumpers no)
		(fp_rect
			(start -0.4318 0.9525)
			(end 0.4318 -0.9525)
			(stroke
				(width 0)
				(type default)
			)
			(fill no)
			(layer "F.CrtYd")
		)
		(fp_rect
			(start -0.4318 0.9525)
			(end 0.4318 -0.9525)
			(stroke
				(width 0)
				(type default)
			)
			(fill no)
			(layer "F.Fab")
		)
		(pad "1" smd custom
			(at 0 -0.4445 180)
			(size 0.1524 0.1524)
			(layers "F.Cu" "F.Mask" "F.Paste")
			(net "VR_PVCCIN_CPU1_AIREF5")
			(options
				(clearance outline)
				(anchor circle)
			)
			(primitives
				(gr_poly
					(pts
						(arc
							(start 0.3048 -0.2032)
							(mid 0.275042 -0.275042)
							(end 0.2032 -0.3048)
						)
						(arc
							(start -0.2032 -0.3048)
							(mid -0.275042 -0.275042)
							(end -0.3048 -0.2032)
						)
						(arc
							(start -0.3048 0.2032)
							(mid -0.275042 0.275042)
							(end -0.2032 0.3048)
						)
						(arc
							(start 0.2032 0.3048)
							(mid 0.275042 0.275042)
							(end 0.3048 0.2032)
						)
					)
					(width 0)
					(fill yes)
				)
			)
		)
		(pad "2" smd custom
			(at 0 0.4445 180)
			(size 0.1524 0.1524)
			(layers "F.Cu" "F.Mask" "F.Paste")
			(net "ISENSE_PVCCIN_CPU1_PH5_IMON")
			(options
				(clearance outline)
				(anchor circle)
			)
			(primitives
				(gr_poly
					(pts
						(arc
							(start 0.3048 -0.2032)
							(mid 0.275042 -0.275042)
							(end 0.2032 -0.3048)
						)
						(arc
							(start -0.2032 -0.3048)
							(mid -0.275042 -0.275042)
							(end -0.3048 -0.2032)
						)
						(arc
							(start -0.3048 0.2032)
							(mid -0.275042 0.275042)
							(end -0.2032 0.3048)
						)
						(arc
							(start 0.2032 0.3048)
							(mid 0.275042 0.275042)
							(end 0.3048 0.2032)
						)
					)
					(width 0)
					(fill yes)
				)
			)
		)
	)
)
